# T6G (Grand Teton) — schematic netlist excerpt (pin names and nets, part order shuffled) for the footprints in the layout excerpt that follows; sources: Cadence DE-HDL packaged netlist, KiCad conversion of 04192023_DAF0TMB3IC0_F0TG_MB_C_brd_V02_OCP.brd

R1259  Q_RES  0 5% CHIP  pkg 0402LF  page 258 : A = P1V8_AUX_ADC ; B = P1V8_AUX_ADC_TIC
C460  Q_CAP  1UF 4V 20% X6S  pkg 0201  page 356 : A = P0V9_CPU1_RT3_2A_2D ; B = GND
R2911  Q_RES  4.7K 5% EMPTY  pkg 0402LF  page 130 : A = P3V3_AUX ; B = RST_SWB_BIC_BUF_R_N

(kicad_pcb
	(version 20260206)
	(generator "pcbnew")
	(generator_version "10.0")
	(general
		(thickness 1.6)
		(legacy_teardrops no)
	)
	(paper "A4")
	(title_block
		(title "04192023_DAF0TMB3IC0_F0TG_MB_C_brd_V02_OCP.brd")
		(comment 1 "Grand Teton / footprints 7625-7627 of 8354")
	)
	(layers
		(0 "F.Cu" signal "TOP")
		(4 "In1.Cu" signal "GND")
		(6 "In2.Cu" signal "IN1")
		(8 "In3.Cu" signal "GND1")
		(10 "In4.Cu" signal "IN2")
		(12 "In5.Cu" signal "GND2")
		(14 "In6.Cu" signal "IN3")
		(16 "In7.Cu" signal "GND3")
		(18 "In8.Cu" signal "VCC")
		(20 "In9.Cu" signal "VCC1")
		(22 "In10.Cu" signal "GND4")
		(24 "In11.Cu" signal "IN4")
		(26 "In12.Cu" signal "GND5")
		(28 "In13.Cu" signal "IN5")
		(30 "In14.Cu" signal "GND6")
		(32 "In15.Cu" signal "IN6")
		(34 "In16.Cu" signal "GND7")
		(2 "B.Cu" signal "BOTTOM")
		(9 "F.Adhes" user "F.Adhesive")
		(11 "B.Adhes" user "B.Adhesive")
		(13 "F.Paste" user "Package Geometry/Pastemask Top")
		(15 "B.Paste" user "Package Geometry/Pastemask Bottom")
		(5 "F.SilkS" user "Ref Des/Silkscreen Top")
		(7 "B.SilkS" user "Ref Des/Silkscreen Bottom")
		(1 "F.Mask" user "Board Geometry/Soldermask Top")
		(3 "B.Mask" user "Board Geometry/Soldermask Bottom")
		(17 "Dwgs.User" user "User.Drawings")
		(19 "Cmts.User" user "User.Comments")
		(21 "Eco1.User" user "User.Eco1")
		(23 "Eco2.User" user "User.Eco2")
		(25 "Edge.Cuts" user "Board Geometry/Outline")
		(27 "Margin" user)
		(31 "F.CrtYd" user "Package Geometry/Place Bound Top")
		(29 "B.CrtYd" user "Package Geometry/Place Bound Bottom")
		(35 "F.Fab" user "Ref Des/Assembly Top")
		(33 "B.Fab" user "Ref Des/Assembly Bottom")
	)
	(footprint ""
		(layer "B.Cu")
		(at 127.678434 -386.766562 90)
		(property "Reference" "C460"
			(at 0 0 90)
			(layer "B.SilkS")
			(hide yes)
			(effects
				(font
					(size 1.27 1.27)
				)
				(justify mirror)
			)
		)
		(property "Value" ""
			(at 0 0 90)
			(layer "B.Fab")
			(effects
				(font
					(size 1.27 1.27)
				)
				(justify mirror)
			)
		)
		(duplicate_pad_numbers_are_jumpers no)
		(fp_line
			(start 0.299974 -0.150114)
			(end -0.299974 -0.150114)
			(stroke
				(width 0.1)
				(type default)
			)
			(layer "B.Fab")
		)
		(fp_line
			(start -0.299974 -0.150114)
			(end -0.299974 0.150114)
			(stroke
				(width 0.1)
				(type default)
			)
			(layer "B.Fab")
		)
		(fp_line
			(start 0.299974 0.150114)
			(end 0.299974 -0.150114)
			(stroke
				(width 0.1)
				(type default)
			)
			(layer "B.Fab")
		)
		(fp_line
			(start -0.299974 0.150114)
			(end 0.299974 0.150114)
			(stroke
				(width 0.1)
				(type default)
			)
			(layer "B.Fab")
		)
		(pad "1" smd rect
			(at 0.2667 0 270)
			(size 0.3048 0.381)
			(layers "B.Cu" "B.Mask" "B.Paste")
			(net "P0V9_CPU1_RT3_2A_2D")
		)
		(pad "2" smd rect
			(at -0.2667 0 270)
			(size 0.3048 0.381)
			(layers "B.Cu" "B.Mask" "B.Paste")
			(net "GND")
		)
	)
	(footprint ""
		(layer "B.Cu")
		(at 181.182518 -415.616644 -90)
		(property "Reference" "R2911"
			(at 0 0 90)
			(layer "B.SilkS")
			(hide yes)
			(effects
				(font
					(size 1.27 1.27)
				)
				(justify mirror)
			)
		)
		(property "Value" ""
			(at 0 0 90)
			(layer "B.Fab")
			(effects
				(font
					(size 1.27 1.27)
				)
				(justify mirror)
			)
		)
		(duplicate_pad_numbers_are_jumpers no)
		(fp_line
			(start -0.7874 0.4064)
			(end 0.7874 0.4064)
			(stroke
				(width 0.1524)
				(type default)
			)
			(layer "B.SilkS")
		)
		(fp_line
			(start 0.7874 0.4064)
			(end 0.7874 -0.4064)
			(stroke
				(width 0.1524)
				(type default)
			)
			(layer "B.SilkS")
		)
		(fp_line
			(start -0.7874 -0.4064)
			(end -0.7874 0.4064)
			(stroke
				(width 0.1524)
				(type default)
			)
			(layer "B.SilkS")
		)
		(fp_line
			(start 0.7874 -0.4064)
			(end -0.7874 -0.4064)
			(stroke
				(width 0.1524)
				(type default)
			)
			(layer "B.SilkS")
		)
		(fp_line
			(start -0.67945 0.3048)
			(end -0.120396 0.3048)
			(stroke
				(width 0.1)
				(type default)
			)
			(layer "B.Fab")
		)
		(fp_line
			(start -0.120396 0.3048)
			(end -0.120396 0.2794)
			(stroke
				(width 0.1)
				(type default)
			)
			(layer "B.Fab")
		)
		(fp_line
			(start 0.12065 0.3048)
			(end 0.67945 0.3048)
			(stroke
				(width 0.1)
				(type default)
			)
			(layer "B.Fab")
		)
		(fp_line
			(start 0.67945 0.3048)
			(end 0.67945 -0.305054)
			(stroke
				(width 0.1)
				(type default)
			)
			(layer "B.Fab")
		)
		(fp_line
			(start -0.120396 0.2794)
			(end 0.12065 0.2794)
			(stroke
				(width 0.1)
				(type default)
			)
			(layer "B.Fab")
		)
		(fp_line
			(start 0.12065 0.2794)
			(end 0.12065 0.3048)
			(stroke
				(width 0.1)
				(type default)
			)
			(layer "B.Fab")
		)
		(fp_line
			(start -0.12065 -0.2794)
			(end -0.12065 -0.3048)
			(stroke
				(width 0.1)
				(type default)
			)
			(layer "B.Fab")
		)
		(fp_line
			(start 0.12065 -0.2794)
			(end -0.12065 -0.2794)
			(stroke
				(width 0.1)
				(type default)
			)
			(layer "B.Fab")
		)
		(fp_line
			(start -0.67945 -0.3048)
			(end -0.67945 0.3048)
			(stroke
				(width 0.1)
				(type default)
			)
			(layer "B.Fab")
		)
		(fp_line
			(start -0.12065 -0.3048)
			(end -0.67945 -0.3048)
			(stroke
				(width 0.1)
				(type default)
			)
			(layer "B.Fab")
		)
		(fp_line
			(start 0.12065 -0.305054)
			(end 0.12065 -0.2794)
			(stroke
				(width 0.1)
				(type default)
			)
			(layer "B.Fab")
		)
		(fp_line
			(start 0.67945 -0.305054)
			(end 0.12065 -0.305054)
			(stroke
				(width 0.1)
				(type default)
			)
			(layer "B.Fab")
		)
		(pad "1" smd circle
			(at 0.40005 0 90)
			(size 0 0)
			(layers "B.Cu" "B.Mask" "B.Paste")
			(net "P3V3_AUX")
		)
		(pad "2" smd circle
			(at -0.40005 0 90)
			(size 0 0)
			(layers "B.Cu" "B.Mask" "B.Paste")
			(net "RST_SWB_BIC_BUF_R_N")
		)
	)
	(footprint ""
		(layer "B.Cu")
		(at 231.143048 -322.84035)
		(property "Reference" "R1259"
			(at 0 0 0)
			(layer "B.SilkS")
			(hide yes)
			(effects
				(font
					(size 1.27 1.27)
				)
				(justify mirror)
			)
		)
		(property "Value" ""
			(at 0 0 0)
			(layer "B.Fab")
			(effects
				(font
					(size 1.27 1.27)
				)
				(justify mirror)
			)
		)
		(duplicate_pad_numbers_are_jumpers no)
		(fp_line
			(start -0.7874 -0.4064)
			(end -0.7874 0.4064)
			(stroke
				(width 0.1524)
				(type default)
			)
			(layer "B.SilkS")
		)
		(fp_line
			(start -0.7874 0.4064)
			(end 0.7874 0.4064)
			(stroke
				(width 0.1524)
				(type default)
			)
			(layer "B.SilkS")
		)
		(fp_line
			(start 0.7874 -0.4064)
			(end -0.7874 -0.4064)
			(stroke
				(width 0.1524)
				(type default)
			)
			(layer "B.SilkS")
		)
		(fp_line
			(start 0.7874 0.4064)
			(end 0.7874 -0.4064)
			(stroke
				(width 0.1524)
				(type default)
			)
			(layer "B.SilkS")
		)
		(fp_line
			(start -0.67945 -0.3048)
			(end -0.67945 0.3048)
			(stroke
				(width 0.1)
				(type default)
			)
			(layer "B.Fab")
		)
		(fp_line
			(start -0.67945 0.3048)
			(end -0.120396 0.3048)
			(stroke
				(width 0.1)
				(type default)
			)
			(layer "B.Fab")
		)
		(fp_line
			(start -0.12065 -0.3048)
			(end -0.67945 -0.3048)
			(stroke
				(width 0.1)
				(type default)
			)
			(layer "B.Fab")
		)
		(fp_line
			(start -0.12065 -0.2794)
			(end -0.12065 -0.3048)
			(stroke
				(width 0.1)
				(type default)
			)
			(layer "B.Fab")
		)
		(fp_line
			(start -0.120396 0.2794)
			(end 0.12065 0.2794)
			(stroke
				(width 0.1)
				(type default)
			)
			(layer "B.Fab")
		)
		(fp_line
			(start -0.120396 0.3048)
			(end -0.120396 0.2794)
			(stroke
				(width 0.1)
				(type default)
			)
			(layer "B.Fab")
		)
		(fp_line
			(start 0.12065 -0.305054)
			(end 0.12065 -0.2794)
			(stroke
				(width 0.1)
				(type default)
			)
			(layer "B.Fab")
		)
		(fp_line
			(start 0.12065 -0.2794)
			(end -0.12065 -0.2794)
			(stroke
				(width 0.1)
				(type default)
			)
			(layer "B.Fab")
		)
		(fp_line
			(start 0.12065 0.2794)
			(end 0.12065 0.3048)
			(stroke
				(width 0.1)
				(type default)
			)
			(layer "B.Fab")
		)
		(fp_line
			(start 0.12065 0.3048)
			(end 0.67945 0.3048)
			(stroke
				(width 0.1)
				(type default)
			)
			(layer "B.Fab")
		)
		(fp_line
			(start 0.67945 -0.305054)
			(end 0.12065 -0.305054)
			(stroke
				(width 0.1)
				(type default)
			)
			(layer "B.Fab")
		)
		(fp_line
			(start 0.67945 0.3048)
			(end 0.67945 -0.305054)
			(stroke
				(width 0.1)
				(type default)
			)
			(layer "B.Fab")
		)
		(pad "1" smd rect
			(at 0.40005 0)
			(size 0.4572 0.508)
			(layers "B.Cu" "B.Mask" "B.Paste")
			(net "P1V8_AUX_ADC")
		)
		(pad "2" smd rect
			(at -0.40005 0)
			(size 0.4572 0.508)
			(layers "B.Cu" "B.Mask" "B.Paste")
			(net "P1V8_AUX_ADC_TIC")
		)
	)
)
